FILE_TYPE = CONNECTIVITY;
{Allegro Design Entry HDL 16.6-p007 (v16-6-112F) 10/10/2012}
"PAGE_NUMBER" = 43;
0"NC";
1"M_A_DQS_DN<17:0>";
2"M_A_DQS_DP<17:0>";
3"M_A_DQ<63:0>";
4"M_A_CLK_DP<3:0>";
5"M_A_ODT<3:0>";
6"M_A_CS_N<7:0>";
7"M_A_BA<1:0>";
8"M_A_CLK_DN<3:0>";
9"M_A_MA<17:0>";
10"M_A_ECC<7:0>";
11"M_A_CKE<3:0>";
12"M_A_BG<1:0>";
13"PVDDQ_ABC\g";
14"GND\g";
15"GND\g";
16"GND\g";
17"GND\g";
18"PVPP_ABC\g";
19"PVPP_ABC\g";
20"PVTT_ABC\g";
21"P12V_NVDIMM_ABC\g";
22"M_A_VREF";
23"TP_CH_A_DIMM_A0_RFU_1";
24"TP_CH_A_DIMM_A0_RFU_0";
25"TP_CH_A_DIMM_A0_RFU_2";
26"M_A_ECC<1>";
27"SMB_DDR_ABC_VPP_SCL";
28"SMB_DDR_ABC_VPP_SDA";
29"FM_ADR_COMPLETE_ABC_N";
30"M_A_ALERT_N";
31"M_A_ACT_N";
32"M_ABC_RST_N";
33"FM_DIMM_EVENT_COD_N";
34"M_A_PAR";
35"M_A_CS_N<0>";
36"M_A_CKE<0>";
37"M_A_ODT<0>";
38"M_A_ECC<6>";
39"M_A_MA<10>";
40"M_A_MA<2>";
41"M_A_BA<0>";
42"M_A_BG<1>";
43"M_A_BG<0>";
44"M_A_CKE<1>";
45"M_A_CLK_DN<0>";
46"M_A_ECC<0>";
47"M_A_ECC<3>";
48"M_A_ECC<2>";
49"M_A_ECC<5>";
50"M_A_ECC<4>";
51"M_A_ECC<7>";
52"M_A_MA<9>";
53"M_A_MA<8>";
54"M_A_MA<7>";
55"M_A_MA<6>";
56"M_A_MA<5>";
57"M_A_MA<4>";
58"M_A_MA<3>";
59"M_A_MA<1>";
60"M_A_MA<0>";
61"M_A_CS_N<2>";
62"M_A_CS_N<3>";
63"M_A_CLK_DP<0>";
64"M_A_CLK_DN<1>";
65"M_A_BA<1>";
66"M_A_CS_N<1>";
67"M_A_ODT<1>";
68"M_A_CLK_DP<1>";
69"M_A_C<2>";
70"M_A_DQ<4>";
71"M_A_DQ<5>";
72"M_A_DQ<2>";
73"M_A_DQ<3>";
74"M_A_DQ<1>";
75"M_A_DQ<0>";
76"M_A_DQ<14>";
77"M_A_DQ<7>";
78"M_A_DQ<6>";
79"M_A_DQ<8>";
80"M_A_DQ<11>";
81"M_A_DQ<10>";
82"M_A_DQ<13>";
83"M_A_DQ<12>";
84"M_A_DQ<15>";
85"M_A_DQ<9>";
86"M_A_DQ<16>";
87"M_A_DQ<27>";
88"M_A_DQ<17>";
89"M_A_DQ<19>";
90"M_A_DQ<18>";
91"M_A_DQ<20>";
92"M_A_DQ<23>";
93"M_A_DQ<25>";
94"M_A_DQ<24>";
95"M_A_DQ<22>";
96"M_A_DQ<21>";
97"M_A_DQ<37>";
98"M_A_DQ<34>";
99"M_A_DQ<30>";
100"M_A_DQ<26>";
101"M_A_DQ<29>";
102"M_A_DQ<31>";
103"M_A_DQ<33>";
104"M_A_DQ<35>";
105"M_A_DQ<32>";
106"M_A_DQ<28>";
107"M_A_DQ<39>";
108"M_A_DQ<36>";
109"M_A_DQ<38>";
110"M_A_DQ<41>";
111"M_A_DQ<43>";
112"M_A_DQ<42>";
113"M_A_DQ<45>";
114"M_A_DQ<44>";
115"M_A_DQ<47>";
116"M_A_DQ<40>";
117"M_A_DQ<46>";
118"M_A_DQ<49>";
119"M_A_DQ<48>";
120"M_A_DQ<51>";
121"M_A_DQ<52>";
122"M_A_DQ<55>";
123"M_A_DQ<54>";
124"M_A_DQ<57>";
125"M_A_DQ<53>";
126"M_A_DQ<50>";
127"M_A_MA<16>";
128"M_A_MA<15>";
129"M_A_MA<14>";
130"M_A_MA<11>";
131"M_A_MA<17>";
132"M_A_MA<13>";
133"M_A_MA<12>";
134"M_A_DQ<62>";
135"M_A_DQ<63>";
136"M_A_DQ<60>";
137"M_A_DQ<59>";
138"M_A_DQ<56>";
139"M_A_DQ<58>";
140"M_A_DQ<61>";
141"M_A_DQS_DN<9>";
142"M_A_DQS_DP<8>";
143"M_A_DQS_DN<8>";
144"M_A_DQS_DP<7>";
145"M_A_DQS_DN<7>";
146"M_A_DQS_DP<6>";
147"M_A_DQS_DN<6>";
148"M_A_DQS_DP<5>";
149"M_A_DQS_DN<5>";
150"M_A_DQS_DP<4>";
151"M_A_DQS_DN<4>";
152"M_A_DQS_DP<3>";
153"M_A_DQS_DN<3>";
154"M_A_DQS_DP<2>";
155"M_A_DQS_DN<2>";
156"M_A_DQS_DP<1>";
157"M_A_DQS_DN<1>";
158"M_A_DQS_DP<0>";
159"M_A_DQS_DN<0>";
160"M_A_DQS_DP<17>";
161"M_A_DQS_DP<9>";
162"M_A_DQS_DN<17>";
163"M_A_DQS_DP<16>";
164"M_A_DQS_DN<16>";
165"M_A_DQS_DP<15>";
166"M_A_DQS_DN<15>";
167"M_A_DQS_DP<14>";
168"M_A_DQS_DN<14>";
169"M_A_DQS_DP<13>";
170"M_A_DQS_DN<13>";
171"M_A_DQS_DP<12>";
172"M_A_DQS_DN<12>";
173"M_A_DQS_DP<11>";
174"M_A_DQS_DN<11>";
175"M_A_DQS_DP<10>";
176"M_A_DQS_DN<10>";
%"SCONN288_H44441004"
"1","(-2400,2750)","0","mstr_sconn","I1";
;
CDS_SEC"1"
ROOM"DDR4_CH_A"
CDS_LOCATION"J4G1"
SEC"1"
SEC_TYPE"PIP"
CDS_LIB"mstr_sconn"
BOM_COST"MEM"
PACK_TYPE"PIP"
MATERIAL"SCONN"
PART_NUMBER"H44441-004"
LOCATION"J4G1";
"DQ<63>"
$PN"280"134;
"DQ<62>"
$PN"135"135;
"DQ<61>"
$PN"273"136;
"DQ<5>"
$PN"148"70;
"DQ<4>"
$PN"3"71;
"DQ<3>"
$PN"157"72;
"DQ<2>"
$PN"12"73;
"DQ<47>"
$PN"258"117;
"DQ<48>"
$PN"119"118;
"DQ<49>"
$PN"264"119;
"DQ<50>"
$PN"126"120;
"DQ<51>"
$PN"271"126;
"DQ<52>"
$PN"117"125;
"DQ<53>"
$PN"262"121;
"DQ<54>"
$PN"124"122;
"DQ<58>"
$PN"137"137;
"DQ<57>"
$PN"275"138;
"SAVE_N_NC"
$PN"230"29;
"RFU<1>"
$PN"227"23;
"RFU<0>"
$PN"205"24;
"DQ<17>"
$PN"172"86;
"DQ<15>"
$PN"166"76;
"DQ<26>"
$PN"45"87;
"DQ<27>"
$PN"190"100;
"S0_N"
$PN"84"35;
"CKE<0>"
$PN"60"36;
"ODT<1>"
$PN"91"67;
"ODT<0>"
$PN"87"37;
"CB<7>"
$PN"199"38;
"A16_RAS_N"
$PN"82"127;
"A15_CAS_N"
$PN"86"128;
"A14_WE_N"
$PN"228"129;
"A11"
$PN"210"130;
"A10"
$PN"225"39;
"DQ<38>"
$PN"102"107;
"DQ<36>"
$PN"95"97;
"DQ<35>"
$PN"249"98;
"A2"
$PN"216"40;
"ALERT_N"
$PN"208"30;
"ACT_N"
$PN"62"31;
"DQ<0>"
$PN"5"74;
"DQ<1>"
$PN"150"75;
"SA<1>"
$PN"140"16;
"SA<2>"
$PN"238"16;
"VDDSPD"
$PN"284"19;
"SA<0>"
$PN"139"16;
"BA<0>"
$PN"81"41;
"BG<1>"
$PN"207"42;
"BG<0>"
$PN"63"43;
"CK1P"
$PN"218"68;
"VREFCA"
$PN"146"22;
"SDA"
$PN"285"28;
"SCL"
$PN"141"27;
"RFU<2>"
$PN"144"25;
"RESET_N"
$PN"58"32;
"PAR"
$PN"222"34;
"EVENT_N"
$PN"78"33;
"DQ<6>"
$PN"10"77;
"DQ<7>"
$PN"155"78;
"DQ<8>"
$PN"16"85;
"DQ<9>"
$PN"161"79;
"DQ<10>"
$PN"23"80;
"DQ<11>"
$PN"168"81;
"DQ<12>"
$PN"14"82;
"DQ<13>"
$PN"159"83;
"DQ<14>"
$PN"21"84;
"DQ<16>"
$PN"27"88;
"DQ<18>"
$PN"34"89;
"DQ<19>"
$PN"179"90;
"DQ<20>"
$PN"25"96;
"DQ<21>"
$PN"170"91;
"DQ<22>"
$PN"32"92;
"DQ<23>"
$PN"177"95;
"DQ<24>"
$PN"38"93;
"DQ<25>"
$PN"183"94;
"DQ<30>"
$PN"43"102;
"DQ<31>"
$PN"188"99;
"DQ<32>"
$PN"97"103;
"DQ<33>"
$PN"242"105;
"DQ<34>"
$PN"104"104;
"DQ<37>"
$PN"240"108;
"DQ<39>"
$PN"247"109;
"DQ<40>"
$PN"108"110;
"DQ<41>"
$PN"253"116;
"DQ<42>"
$PN"115"111;
"DQ<43>"
$PN"260"112;
"DQ<44>"
$PN"106"113;
"DQ<45>"
$PN"251"114;
"DQ<46>"
$PN"113"115;
"DQ<55>"
$PN"269"123;
"DQ<56>"
$PN"130"124;
"DQ<59>"
$PN"282"139;
"DQ<60>"
$PN"128"140;
"CKE<1>"
$PN"203"44;
"CK0N"
$PN"75"45;
"CB<0>"
$PN"49"26;
"CB<1>"
$PN"194"46;
"CB<2>"
$PN"56"47;
"CB<3>"
$PN"201"48;
"CB<4>"
$PN"47"49;
"CB<5>"
$PN"192"50;
"CB<6>"
$PN"54"51;
"A9"
$PN"66"52;
"A8"
$PN"68"53;
"A7"
$PN"211"54;
"A6"
$PN"69"55;
"A5"
$PN"213"56;
"A4"
$PN"214"57;
"A3"
$PN"71"58;
"A17"
$PN"234"131;
"A13"
$PN"232"132;
"A12"
$PN"65"133;
"A1"
$PN"72"59;
"A0"
$PN"79"60;
"C<2>"
$PN"235"69;
"DQ<28>"
$PN"36"101;
"DQ<29>"
$PN"181"106;
"S1_N"
$PN"89"66;
"S2_N_C<0>"
$PN"93"61;
"S3_N_C<1>"
$PN"237"62;
"CK0P"
$PN"74"63;
"CK1N"
$PN"219"64;
"BA<1>"
$PN"224"65;
%"TAP"
"6","(-1600,4100)","2","mstr_standard","I127";
;
HDL_TAP"TRUE"
BODY_TYPE"PLUMBING"
CDS_LIB"mstr_standard";
"B \NAC \NWC"3;
"S \NAC"
BN"56"138;
%"TAP"
"6","(-1600,4150)","2","mstr_standard","I128";
;
HDL_TAP"TRUE"
BODY_TYPE"PLUMBING"
CDS_LIB"mstr_standard";
"B \NAC \NWC"3;
"S \NAC"
BN"59"137;
%"TAP"
"6","(-1600,4200)","2","mstr_standard","I129";
;
HDL_TAP"TRUE"
BODY_TYPE"PLUMBING"
CDS_LIB"mstr_standard";
"B \NAC \NWC"3;
"S \NAC"
BN"58"139;
%"TAP"
"6","(-1600,4250)","2","mstr_standard","I130";
;
HDL_TAP"TRUE"
BODY_TYPE"PLUMBING"
CDS_LIB"mstr_standard";
"B \NAC \NWC"3;
"S \NAC"
BN"61"140;
%"TAP"
"6","(-1600,4350)","2","mstr_standard","I131";
;
HDL_TAP"TRUE"
BODY_TYPE"PLUMBING"
CDS_LIB"mstr_standard";
"B \NAC \NWC"3;
"S \NAC"
BN"63"135;
%"TAP"
"6","(-1600,4300)","2","mstr_standard","I132";
;
HDL_TAP"TRUE"
BODY_TYPE"PLUMBING"
CDS_LIB"mstr_standard";
"B \NAC \NWC"3;
"S \NAC"
BN"60"136;
%"TAP"
"6","(-1600,4400)","2","mstr_standard","I133";
;
HDL_TAP"TRUE"
BODY_TYPE"PLUMBING"
CDS_LIB"mstr_standard";
"B \NAC \NWC"3;
"S \NAC"
BN"62"134;
%"TAP"
"6","(-1600,3750)","2","mstr_standard","I134";
;
HDL_TAP"TRUE"
BODY_TYPE"PLUMBING"
CDS_LIB"mstr_standard";
"B \NAC \NWC"3;
"S \NAC"
BN"51"120;
%"TAP"
"6","(-1600,3800)","2","mstr_standard","I135";
;
HDL_TAP"TRUE"
BODY_TYPE"PLUMBING"
CDS_LIB"mstr_standard";
"B \NAC \NWC"3;
"S \NAC"
BN"50"126;
%"TAP"
"6","(-1600,3900)","2","mstr_standard","I136";
;
HDL_TAP"TRUE"
BODY_TYPE"PLUMBING"
CDS_LIB"mstr_standard";
"B \NAC \NWC"3;
"S \NAC"
BN"52"121;
%"TAP"
"6","(-1600,3850)","2","mstr_standard","I137";
;
HDL_TAP"TRUE"
BODY_TYPE"PLUMBING"
CDS_LIB"mstr_standard";
"B \NAC \NWC"3;
"S \NAC"
BN"53"125;
%"TAP"
"6","(-1600,3950)","2","mstr_standard","I138";
;
HDL_TAP"TRUE"
BODY_TYPE"PLUMBING"
CDS_LIB"mstr_standard";
"B \NAC \NWC"3;
"S \NAC"
BN"55"122;
%"TAP"
"6","(-1600,4000)","2","mstr_standard","I139";
;
HDL_TAP"TRUE"
BODY_TYPE"PLUMBING"
CDS_LIB"mstr_standard";
"B \NAC \NWC"3;
"S \NAC"
BN"54"123;
%"TAP"
"6","(-1600,4050)","2","mstr_standard","I140";
;
HDL_TAP"TRUE"
BODY_TYPE"PLUMBING"
CDS_LIB"mstr_standard";
"B \NAC \NWC"3;
"S \NAC"
BN"57"124;
%"TAP"
"6","(-1600,3700)","2","mstr_standard","I141";
;
HDL_TAP"TRUE"
BODY_TYPE"PLUMBING"
CDS_LIB"mstr_standard";
"B \NAC \NWC"3;
"S \NAC"
BN"48"119;
%"TAP"
"6","(-1600,2750)","2","mstr_standard","I142";
;
HDL_TAP"TRUE"
BODY_TYPE"PLUMBING"
CDS_LIB"mstr_standard";
"B \NAC \NWC"3;
"S \NAC"
BN"31"102;
%"TAP"
"6","(-1600,2700)","2","mstr_standard","I143";
;
HDL_TAP"TRUE"
BODY_TYPE"PLUMBING"
CDS_LIB"mstr_standard";
"B \NAC \NWC"3;
"S \NAC"
BN"28"106;
%"TAP"
"6","(-1600,2800)","2","mstr_standard","I144";
;
HDL_TAP"TRUE"
BODY_TYPE"PLUMBING"
CDS_LIB"mstr_standard";
"B \NAC \NWC"3;
"S \NAC"
BN"30"99;
%"TAP"
"6","(-1600,2850)","2","mstr_standard","I145";
;
HDL_TAP"TRUE"
BODY_TYPE"PLUMBING"
CDS_LIB"mstr_standard";
"B \NAC \NWC"3;
"S \NAC"
BN"33"103;
%"TAP"
"6","(-1600,2950)","2","mstr_standard","I146";
;
HDL_TAP"TRUE"
BODY_TYPE"PLUMBING"
CDS_LIB"mstr_standard";
"B \NAC \NWC"3;
"S \NAC"
BN"35"104;
%"TAP"
"6","(-1600,2900)","2","mstr_standard","I147";
;
HDL_TAP"TRUE"
BODY_TYPE"PLUMBING"
CDS_LIB"mstr_standard";
"B \NAC \NWC"3;
"S \NAC"
BN"32"105;
%"TAP"
"6","(-1600,3000)","2","mstr_standard","I148";
;
HDL_TAP"TRUE"
BODY_TYPE"PLUMBING"
CDS_LIB"mstr_standard";
"B \NAC \NWC"3;
"S \NAC"
BN"34"98;
%"TAP"
"6","(-1600,3050)","2","mstr_standard","I149";
;
HDL_TAP"TRUE"
BODY_TYPE"PLUMBING"
CDS_LIB"mstr_standard";
"B \NAC \NWC"3;
"S \NAC"
BN"37"97;
%"TAP"
"6","(-1600,3100)","2","mstr_standard","I150";
;
HDL_TAP"TRUE"
BODY_TYPE"PLUMBING"
CDS_LIB"mstr_standard";
"B \NAC \NWC"3;
"S \NAC"
BN"36"108;
%"TAP"
"6","(-1600,3200)","2","mstr_standard","I151";
;
HDL_TAP"TRUE"
BODY_TYPE"PLUMBING"
CDS_LIB"mstr_standard";
"B \NAC \NWC"3;
"S \NAC"
BN"38"109;
%"TAP"
"6","(-1600,3150)","2","mstr_standard","I152";
;
HDL_TAP"TRUE"
BODY_TYPE"PLUMBING"
CDS_LIB"mstr_standard";
"B \NAC \NWC"3;
"S \NAC"
BN"39"107;
%"TAP"
"6","(-1600,3250)","2","mstr_standard","I153";
;
HDL_TAP"TRUE"
BODY_TYPE"PLUMBING"
CDS_LIB"mstr_standard";
"B \NAC \NWC"3;
"S \NAC"
BN"41"110;
%"TAP"
"6","(-1600,3300)","2","mstr_standard","I154";
;
HDL_TAP"TRUE"
BODY_TYPE"PLUMBING"
CDS_LIB"mstr_standard";
"B \NAC \NWC"3;
"S \NAC"
BN"40"116;
%"TAP"
"6","(-1600,3350)","2","mstr_standard","I155";
;
HDL_TAP"TRUE"
BODY_TYPE"PLUMBING"
CDS_LIB"mstr_standard";
"B \NAC \NWC"3;
"S \NAC"
BN"43"111;
%"TAP"
"6","(-1600,3450)","2","mstr_standard","I156";
;
HDL_TAP"TRUE"
BODY_TYPE"PLUMBING"
CDS_LIB"mstr_standard";
"B \NAC \NWC"3;
"S \NAC"
BN"45"113;
%"TAP"
"6","(-1600,3400)","2","mstr_standard","I157";
;
HDL_TAP"TRUE"
BODY_TYPE"PLUMBING"
CDS_LIB"mstr_standard";
"B \NAC \NWC"3;
"S \NAC"
BN"42"112;
%"TAP"
"6","(-1600,3500)","2","mstr_standard","I158";
;
HDL_TAP"TRUE"
BODY_TYPE"PLUMBING"
CDS_LIB"mstr_standard";
"B \NAC \NWC"3;
"S \NAC"
BN"44"114;
%"TAP"
"6","(-1600,3550)","2","mstr_standard","I159";
;
HDL_TAP"TRUE"
BODY_TYPE"PLUMBING"
CDS_LIB"mstr_standard";
"B \NAC \NWC"3;
"S \NAC"
BN"47"115;
%"TAP"
"6","(-1600,3650)","2","mstr_standard","I160";
;
HDL_TAP"TRUE"
BODY_TYPE"PLUMBING"
CDS_LIB"mstr_standard";
"B \NAC \NWC"3;
"S \NAC"
BN"49"118;
%"TAP"
"6","(-1600,3600)","2","mstr_standard","I161";
;
HDL_TAP"TRUE"
BODY_TYPE"PLUMBING"
CDS_LIB"mstr_standard";
"B \NAC \NWC"3;
"S \NAC"
BN"46"117;
%"TAP"
"6","(-1600,2050)","2","mstr_standard","I162";
;
HDL_TAP"TRUE"
BODY_TYPE"PLUMBING"
CDS_LIB"mstr_standard";
"B \NAC \NWC"3;
"S \NAC"
BN"17"88;
%"TAP"
"6","(-1600,2000)","2","mstr_standard","I163";
;
HDL_TAP"TRUE"
BODY_TYPE"PLUMBING"
CDS_LIB"mstr_standard";
"B \NAC \NWC"3;
"S \NAC"
BN"14"76;
%"TAP"
"6","(-1600,2100)","2","mstr_standard","I164";
;
HDL_TAP"TRUE"
BODY_TYPE"PLUMBING"
CDS_LIB"mstr_standard";
"B \NAC \NWC"3;
"S \NAC"
BN"16"86;
%"TAP"
"6","(-1600,2150)","2","mstr_standard","I165";
;
HDL_TAP"TRUE"
BODY_TYPE"PLUMBING"
CDS_LIB"mstr_standard";
"B \NAC \NWC"3;
"S \NAC"
BN"19"89;
%"TAP"
"6","(-1600,2200)","2","mstr_standard","I166";
;
HDL_TAP"TRUE"
BODY_TYPE"PLUMBING"
CDS_LIB"mstr_standard";
"B \NAC \NWC"3;
"S \NAC"
BN"18"90;
%"TAP"
"6","(-1600,2300)","2","mstr_standard","I167";
;
HDL_TAP"TRUE"
BODY_TYPE"PLUMBING"
CDS_LIB"mstr_standard";
"B \NAC \NWC"3;
"S \NAC"
BN"20"91;
%"TAP"
"6","(-1600,2250)","2","mstr_standard","I168";
;
HDL_TAP"TRUE"
BODY_TYPE"PLUMBING"
CDS_LIB"mstr_standard";
"B \NAC \NWC"3;
"S \NAC"
BN"21"96;
%"TAP"
"6","(-1600,2350)","2","mstr_standard","I169";
;
HDL_TAP"TRUE"
BODY_TYPE"PLUMBING"
CDS_LIB"mstr_standard";
"B \NAC \NWC"3;
"S \NAC"
BN"23"92;
%"TAP"
"6","(-1600,2400)","2","mstr_standard","I170";
;
HDL_TAP"TRUE"
BODY_TYPE"PLUMBING"
CDS_LIB"mstr_standard";
"B \NAC \NWC"3;
"S \NAC"
BN"22"95;
%"TAP"
"6","(-1600,2500)","2","mstr_standard","I171";
;
HDL_TAP"TRUE"
BODY_TYPE"PLUMBING"
CDS_LIB"mstr_standard";
"B \NAC \NWC"3;
"S \NAC"
BN"24"94;
%"TAP"
"6","(-1600,2450)","2","mstr_standard","I172";
;
HDL_TAP"TRUE"
BODY_TYPE"PLUMBING"
CDS_LIB"mstr_standard";
"B \NAC \NWC"3;
"S \NAC"
BN"25"93;
%"TAP"
"6","(-1600,2550)","2","mstr_standard","I173";
;
HDL_TAP"TRUE"
BODY_TYPE"PLUMBING"
CDS_LIB"mstr_standard";
"B \NAC \NWC"3;
"S \NAC"
BN"27"87;
%"TAP"
"6","(-1600,2600)","2","mstr_standard","I174";
;
HDL_TAP"TRUE"
BODY_TYPE"PLUMBING"
CDS_LIB"mstr_standard";
"B \NAC \NWC"3;
"S \NAC"
BN"26"100;
%"TAP"
"6","(-1600,2650)","2","mstr_standard","I175";
;
HDL_TAP"TRUE"
BODY_TYPE"PLUMBING"
CDS_LIB"mstr_standard";
"B \NAC \NWC"3;
"S \NAC"
BN"29"101;
%"TAP"
"6","(-1600,1700)","2","mstr_standard","I176";
;
HDL_TAP"TRUE"
BODY_TYPE"PLUMBING"
CDS_LIB"mstr_standard";
"B \NAC \NWC"3;
"S \NAC"
BN"8"79;
%"TAP"
"6","(-1600,1750)","2","mstr_standard","I177";
;
HDL_TAP"TRUE"
BODY_TYPE"PLUMBING"
CDS_LIB"mstr_standard";
"B \NAC \NWC"3;
"S \NAC"
BN"11"80;
%"TAP"
"6","(-1600,1850)","2","mstr_standard","I178";
;
HDL_TAP"TRUE"
BODY_TYPE"PLUMBING"
CDS_LIB"mstr_standard";
"B \NAC \NWC"3;
"S \NAC"
BN"13"82;
%"TAP"
"6","(-1600,1800)","2","mstr_standard","I179";
;
HDL_TAP"TRUE"
BODY_TYPE"PLUMBING"
CDS_LIB"mstr_standard";
"B \NAC \NWC"3;
"S \NAC"
BN"10"81;
%"TAP"
"6","(-1600,1900)","2","mstr_standard","I180";
;
HDL_TAP"TRUE"
BODY_TYPE"PLUMBING"
CDS_LIB"mstr_standard";
"B \NAC \NWC"3;
"S \NAC"
BN"12"83;
%"TAP"
"6","(-1600,1950)","2","mstr_standard","I181";
;
HDL_TAP"TRUE"
BODY_TYPE"PLUMBING"
CDS_LIB"mstr_standard";
"B \NAC \NWC"3;
"S \NAC"
BN"15"84;
%"TAP"
"6","(-1600,1650)","2","mstr_standard","I182";
;
HDL_TAP"TRUE"
BODY_TYPE"PLUMBING"
CDS_LIB"mstr_standard";
"B \NAC \NWC"3;
"S \NAC"
BN"9"85;
%"TAP"
"6","(-1600,1250)","2","mstr_standard","I183";
;
HDL_TAP"TRUE"
BODY_TYPE"PLUMBING"
CDS_LIB"mstr_standard";
"B \NAC \NWC"3;
"S \NAC"
BN"1"74;
%"TAP"
"6","(-1600,1350)","2","mstr_standard","I184";
;
HDL_TAP"TRUE"
BODY_TYPE"PLUMBING"
CDS_LIB"mstr_standard";
"B \NAC \NWC"3;
"S \NAC"
BN"3"73;
%"TAP"
"6","(-1600,1300)","2","mstr_standard","I185";
;
HDL_TAP"TRUE"
BODY_TYPE"PLUMBING"
CDS_LIB"mstr_standard";
"B \NAC \NWC"3;
"S \NAC"
BN"0"75;
%"TAP"
"6","(-1600,1400)","2","mstr_standard","I186";
;
HDL_TAP"TRUE"
BODY_TYPE"PLUMBING"
CDS_LIB"mstr_standard";
"B \NAC \NWC"3;
"S \NAC"
BN"2"72;
%"TAP"
"6","(-1600,1450)","2","mstr_standard","I187";
;
HDL_TAP"TRUE"
BODY_TYPE"PLUMBING"
CDS_LIB"mstr_standard";
"B \NAC \NWC"3;
"S \NAC"
BN"5"71;
%"TAP"
"6","(-1600,1500)","2","mstr_standard","I188";
;
HDL_TAP"TRUE"
BODY_TYPE"PLUMBING"
CDS_LIB"mstr_standard";
"B \NAC \NWC"3;
"S \NAC"
BN"4"70;
%"TAP"
"6","(-1600,1600)","2","mstr_standard","I189";
;
HDL_TAP"TRUE"
BODY_TYPE"PLUMBING"
CDS_LIB"mstr_standard";
"B \NAC \NWC"3;
"S \NAC"
BN"6"78;
%"TAP"
"6","(-1600,1550)","2","mstr_standard","I190";
;
HDL_TAP"TRUE"
BODY_TYPE"PLUMBING"
CDS_LIB"mstr_standard";
"B \NAC \NWC"3;
"S \NAC"
BN"7"77;
%"TAP"
"6","(650,4200)","2","mstr_standard","I192";
;
HDL_TAP"TRUE"
BODY_TYPE"PLUMBING"
CDS_LIB"mstr_standard";
"B \NAC \NWC"2;
"S \NAC"
BN"10"175;
%"TAP"
"6","(650,4300)","2","mstr_standard","I193";
;
HDL_TAP"TRUE"
BODY_TYPE"PLUMBING"
CDS_LIB"mstr_standard";
"B \NAC \NWC"2;
"S \NAC"
BN"11"173;
%"TAP"
"6","(650,4000)","2","mstr_standard","I194";
;
HDL_TAP"TRUE"
BODY_TYPE"PLUMBING"
CDS_LIB"mstr_standard";
"B \NAC \NWC"2;
"S \NAC"
BN"8"142;
%"TAP"
"6","(650,4100)","2","mstr_standard","I195";
;
HDL_TAP"TRUE"
BODY_TYPE"PLUMBING"
CDS_LIB"mstr_standard";
"B \NAC \NWC"2;
"S \NAC"
BN"9"161;
%"TAP"
"6","(650,3700)","2","mstr_standard","I196";
;
HDL_TAP"TRUE"
BODY_TYPE"PLUMBING"
CDS_LIB"mstr_standard";
"B \NAC \NWC"2;
"S \NAC"
BN"5"148;
%"TAP"
"6","(650,3800)","2","mstr_standard","I197";
;
HDL_TAP"TRUE"
BODY_TYPE"PLUMBING"
CDS_LIB"mstr_standard";
"B \NAC \NWC"2;
"S \NAC"
BN"6"146;
%"TAP"
"6","(650,3900)","2","mstr_standard","I198";
;
HDL_TAP"TRUE"
BODY_TYPE"PLUMBING"
CDS_LIB"mstr_standard";
"B \NAC \NWC"2;
"S \NAC"
BN"7"144;
%"TAP"
"6","(650,3500)","2","mstr_standard","I199";
;
HDL_TAP"TRUE"
BODY_TYPE"PLUMBING"
CDS_LIB"mstr_standard";
"B \NAC \NWC"2;
"S \NAC"
BN"3"152;
%"SCONN288_H44441004"
"2","(-50,4050)","0","mstr_sconn","I2";
;
CDS_SEC"2"
ROOM"DDR4_CH_A"
CDS_LOCATION"J4G1"
SEC"2"
SEC_TYPE"PIP"
CDS_LIB"mstr_sconn"
BOM_COST"MEM"
PACK_TYPE"PIP"
MATERIAL"SCONN"
PART_NUMBER"H44441-004"
LOCATION"J4G1";
"DQS17P"
$PN"51"160;
"DQS9P"
$PN"7"161;
"DQS9N"
$PN"8"141;
"DQS8P"
$PN"197"142;
"DQS8N"
$PN"196"143;
"DQS7P"
$PN"278"144;
"DQS7N"
$PN"277"145;
"DQS6P"
$PN"267"146;
"DQS6N"
$PN"266"147;
"DQS5P"
$PN"256"148;
"DQS5N"
$PN"255"149;
"DQS4P"
$PN"245"150;
"DQS4N"
$PN"244"151;
"DQS3P"
$PN"186"152;
"DQS3N"
$PN"185"153;
"DQS2P"
$PN"175"154;
"DQS2N"
$PN"174"155;
"DQS1P"
$PN"164"156;
"DQS1N"
$PN"163"157;
"DQS17N"
$PN"52"162;
"DQS16P"
$PN"132"163;
"DQS16N"
$PN"133"164;
"DQS15P"
$PN"121"165;
"DQS15N"
$PN"122"166;
"DQS14P"
$PN"110"167;
"DQS14N"
$PN"111"168;
"DQS13P"
$PN"99"169;
"DQS13N"
$PN"100"170;
"DQS12P"
$PN"40"171;
"DQS12N"
$PN"41"172;
"DQS11P"
$PN"29"173;
"DQS11N"
$PN"30"174;
"DQS10P"
$PN"18"175;
"DQS10N"
$PN"19"176;
"DQS0P"
$PN"153"158;
"DQS0N"
$PN"152"159;
%"TAP"
"6","(650,3600)","2","mstr_standard","I200";
;
HDL_TAP"TRUE"
BODY_TYPE"PLUMBING"
CDS_LIB"mstr_standard";
"B \NAC \NWC"2;
"S \NAC"
BN"4"150;
%"TAP"
"6","(650,3200)","2","mstr_standard","I201";
;
HDL_TAP"TRUE"
BODY_TYPE"PLUMBING"
CDS_LIB"mstr_standard";
"B \NAC \NWC"2;
"S \NAC"
BN"0"158;
%"TAP"
"6","(650,3300)","2","mstr_standard","I202";
;
HDL_TAP"TRUE"
BODY_TYPE"PLUMBING"
CDS_LIB"mstr_standard";
"B \NAC \NWC"2;
"S \NAC"
BN"1"156;
%"TAP"
"6","(650,3400)","2","mstr_standard","I203";
;
HDL_TAP"TRUE"
BODY_TYPE"PLUMBING"
CDS_LIB"mstr_standard";
"B \NAC \NWC"2;
"S \NAC"
BN"2"154;
%"TAP"
"6","(650,4700)","2","mstr_standard","I205";
;
HDL_TAP"TRUE"
BODY_TYPE"PLUMBING"
CDS_LIB"mstr_standard";
"B \NAC \NWC"2;
"S \NAC"
BN"15"165;
%"TAP"
"6","(650,4900)","2","mstr_standard","I206";
;
HDL_TAP"TRUE"
BODY_TYPE"PLUMBING"
CDS_LIB"mstr_standard";
"B \NAC \NWC"2;
"S \NAC"
BN"17"160;
%"TAP"
"6","(650,4800)","2","mstr_standard","I207";
;
HDL_TAP"TRUE"
BODY_TYPE"PLUMBING"
CDS_LIB"mstr_standard";
"B \NAC \NWC"2;
"S \NAC"
BN"16"163;
%"TAP"
"6","(650,4500)","2","mstr_standard","I208";
;
HDL_TAP"TRUE"
BODY_TYPE"PLUMBING"
CDS_LIB"mstr_standard";
"B \NAC \NWC"2;
"S \NAC"
BN"13"169;
%"TAP"
"6","(650,4600)","2","mstr_standard","I209";
;
HDL_TAP"TRUE"
BODY_TYPE"PLUMBING"
CDS_LIB"mstr_standard";
"B \NAC \NWC"2;
"S \NAC"
BN"14"167;
%"TAP"
"6","(650,4400)","2","mstr_standard","I210";
;
HDL_TAP"TRUE"
BODY_TYPE"PLUMBING"
CDS_LIB"mstr_standard";
"B \NAC \NWC"2;
"S \NAC"
BN"12"171;
%"TAP"
"6","(850,4850)","2","mstr_standard","I212";
;
HDL_TAP"TRUE"
BODY_TYPE"PLUMBING"
CDS_LIB"mstr_standard";
"B \NAC \NWC"1;
"S \NAC"
BN"17"162;
%"TAP"
"6","(850,4750)","2","mstr_standard","I213";
;
HDL_TAP"TRUE"
BODY_TYPE"PLUMBING"
CDS_LIB"mstr_standard";
"B \NAC \NWC"1;
"S \NAC"
BN"16"164;
%"TAP"
"6","(850,4650)","2","mstr_standard","I214";
;
HDL_TAP"TRUE"
BODY_TYPE"PLUMBING"
CDS_LIB"mstr_standard";
"B \NAC \NWC"1;
"S \NAC"
BN"15"166;
%"TAP"
"6","(850,4550)","2","mstr_standard","I215";
;
HDL_TAP"TRUE"
BODY_TYPE"PLUMBING"
CDS_LIB"mstr_standard";
"B \NAC \NWC"1;
"S \NAC"
BN"14"168;
%"TAP"
"6","(850,4450)","2","mstr_standard","I216";
;
HDL_TAP"TRUE"
BODY_TYPE"PLUMBING"
CDS_LIB"mstr_standard";
"B \NAC \NWC"1;
"S \NAC"
BN"13"170;
%"TAP"
"6","(850,4350)","2","mstr_standard","I217";
;
HDL_TAP"TRUE"
BODY_TYPE"PLUMBING"
CDS_LIB"mstr_standard";
"B \NAC \NWC"1;
"S \NAC"
BN"12"172;
%"TAP"
"6","(850,4250)","2","mstr_standard","I218";
;
HDL_TAP"TRUE"
BODY_TYPE"PLUMBING"
CDS_LIB"mstr_standard";
"B \NAC \NWC"1;
"S \NAC"
BN"11"174;
%"TAP"
"6","(850,4150)","2","mstr_standard","I219";
;
HDL_TAP"TRUE"
BODY_TYPE"PLUMBING"
CDS_LIB"mstr_standard";
"B \NAC \NWC"1;
"S \NAC"
BN"10"176;
%"TAP"
"6","(-3150,4400)","0","mstr_standard","I22";
;
HDL_TAP"TRUE"
BODY_TYPE"PLUMBING"
CDS_LIB"mstr_standard";
"B \NAC \NWC"9;
"S \NAC"
BN"17"131;
%"TAP"
"6","(850,4050)","2","mstr_standard","I220";
;
HDL_TAP"TRUE"
BODY_TYPE"PLUMBING"
CDS_LIB"mstr_standard";
"B \NAC \NWC"1;
"S \NAC"
BN"9"141;
%"TAP"
"6","(850,3950)","2","mstr_standard","I221";
;
HDL_TAP"TRUE"
BODY_TYPE"PLUMBING"
CDS_LIB"mstr_standard";
"B \NAC \NWC"1;
"S \NAC"
BN"8"143;
%"TAP"
"6","(850,3850)","2","mstr_standard","I222";
;
HDL_TAP"TRUE"
BODY_TYPE"PLUMBING"
CDS_LIB"mstr_standard";
"B \NAC \NWC"1;
"S \NAC"
BN"7"145;
%"TAP"
"6","(850,3750)","2","mstr_standard","I223";
;
HDL_TAP"TRUE"
BODY_TYPE"PLUMBING"
CDS_LIB"mstr_standard";
"B \NAC \NWC"1;
"S \NAC"
BN"6"147;
%"TAP"
"6","(850,3650)","2","mstr_standard","I224";
;
HDL_TAP"TRUE"
BODY_TYPE"PLUMBING"
CDS_LIB"mstr_standard";
"B \NAC \NWC"1;
"S \NAC"
BN"5"149;
%"TAP"
"6","(850,3550)","2","mstr_standard","I225";
;
HDL_TAP"TRUE"
BODY_TYPE"PLUMBING"
CDS_LIB"mstr_standard";
"B \NAC \NWC"1;
"S \NAC"
BN"4"151;
%"TAP"
"6","(850,3450)","2","mstr_standard","I226";
;
HDL_TAP"TRUE"
BODY_TYPE"PLUMBING"
CDS_LIB"mstr_standard";
"B \NAC \NWC"1;
"S \NAC"
BN"3"153;
%"TAP"
"6","(850,3350)","2","mstr_standard","I227";
;
HDL_TAP"TRUE"
BODY_TYPE"PLUMBING"
CDS_LIB"mstr_standard";
"B \NAC \NWC"1;
"S \NAC"
BN"2"155;
%"TAP"
"6","(850,3250)","2","mstr_standard","I228";
;
HDL_TAP"TRUE"
BODY_TYPE"PLUMBING"
CDS_LIB"mstr_standard";
"B \NAC \NWC"1;
"S \NAC"
BN"1"157;
%"TAP"
"6","(850,3150)","2","mstr_standard","I229";
;
HDL_TAP"TRUE"
BODY_TYPE"PLUMBING"
CDS_LIB"mstr_standard";
"B \NAC \NWC"1;
"S \NAC"
BN"0"159;
%"TAP"
"6","(-3150,4350)","0","mstr_standard","I23";
;
HDL_TAP"TRUE"
BODY_TYPE"PLUMBING"
CDS_LIB"mstr_standard";
"B \NAC \NWC"9;
"S \NAC"
BN"16"127;
%"TAP"
"6","(-3150,2450)","0","mstr_standard","I235";
;
HDL_TAP"TRUE"
BODY_TYPE"PLUMBING"
CDS_LIB"mstr_standard";
"B \NAC \NWC"5;
"S \NAC"
BN"0"37;
%"TAP"
"6","(-3150,2500)","0","mstr_standard","I236";
;
HDL_TAP"TRUE"
BODY_TYPE"PLUMBING"
CDS_LIB"mstr_standard";
"B \NAC \NWC"5;
"S \NAC"
BN"1"67;
%"TAP"
"6","(-3150,2650)","0","mstr_standard","I238";
;
HDL_TAP"TRUE"
BODY_TYPE"PLUMBING"
CDS_LIB"mstr_standard";
"B \NAC \NWC"11;
"S \NAC"
BN"1"44;
%"TAP"
"6","(-3150,2600)","0","mstr_standard","I239";
;
HDL_TAP"TRUE"
BODY_TYPE"PLUMBING"
CDS_LIB"mstr_standard";
"B \NAC \NWC"11;
"S \NAC"
BN"0"36;
%"TAP"
"6","(-3150,4300)","0","mstr_standard","I24";
;
HDL_TAP"TRUE"
BODY_TYPE"PLUMBING"
CDS_LIB"mstr_standard";
"B \NAC \NWC"9;
"S \NAC"
BN"15"128;
%"TAP"
"6","(-3150,2900)","0","mstr_standard","I241";
;
HDL_TAP"TRUE"
BODY_TYPE"PLUMBING"
CDS_LIB"mstr_standard";
"B \NAC \NWC"6;
"S \NAC"
BN"3"62;
%"TAP"
"6","(-3150,2850)","0","mstr_standard","I242";
;
HDL_TAP"TRUE"
BODY_TYPE"PLUMBING"
CDS_LIB"mstr_standard";
"B \NAC \NWC"6;
"S \NAC"
BN"2"61;
%"TAP"
"6","(-3150,2800)","0","mstr_standard","I243";
;
HDL_TAP"TRUE"
BODY_TYPE"PLUMBING"
CDS_LIB"mstr_standard";
"B \NAC \NWC"6;
"S \NAC"
BN"1"66;
%"TAP"
"6","(-3150,2750)","0","mstr_standard","I244";
;
HDL_TAP"TRUE"
BODY_TYPE"PLUMBING"
CDS_LIB"mstr_standard";
"B \NAC \NWC"6;
"S \NAC"
BN"0"35;
%"TAP"
"6","(-3350,3050)","0","mstr_standard","I247";
;
HDL_TAP"TRUE"
BODY_TYPE"PLUMBING"
CDS_LIB"mstr_standard";
"B \NAC \NWC"8;
"S \NAC"
BN"0"45;
%"TAP"
"6","(-3150,4250)","0","mstr_standard","I25";
;
HDL_TAP"TRUE"
BODY_TYPE"PLUMBING"
CDS_LIB"mstr_standard";
"B \NAC \NWC"9;
"S \NAC"
BN"14"129;
%"TAP"
"6","(-3150,3200)","0","mstr_standard","I250";
;
HDL_TAP"TRUE"
BODY_TYPE"PLUMBING"
CDS_LIB"mstr_standard";
"B \NAC \NWC"4;
"S \NAC"
BN"1"68;
%"TAP"
"6","(-3150,3100)","0","mstr_standard","I252";
;
HDL_TAP"TRUE"
BODY_TYPE"PLUMBING"
CDS_LIB"mstr_standard";
"B \NAC \NWC"4;
"S \NAC"
BN"0"63;
%"TAP"
"6","(-3350,3150)","0","mstr_standard","I254";
;
HDL_TAP"TRUE"
BODY_TYPE"PLUMBING"
CDS_LIB"mstr_standard";
"B \NAC \NWC"8;
"S \NAC"
BN"1"64;
%"SCONN288_H44441004"
"3","(1750,2450)","0","mstr_sconn","I259";
;
CDS_SEC"3"
ROOM"DDR4_CH_A"
CDS_LOCATION"J4G1"
SEC"3"
SEC_TYPE"PIP"
CDS_LIB"mstr_sconn"
BOM_COST"MEM"
PACK_TYPE"PIP"
MATERIAL"SCONN"
PART_NUMBER"H44441-004"
LOCATION"J4G1";
"VSS<93>"
$PN"2"14;
"VSS<92>"
$PN"4"14;
"VSS<91>"
$PN"6"14;
"VSS<90>"
$PN"9"14;
"VSS<89>"
$PN"11"14;
"VSS<88>"
$PN"13"14;
"VSS<0>"
$PN"283"15;
"VSS<1>"
$PN"281"15;
"VSS<2>"
$PN"279"15;
"VSS<3>"
$PN"276"15;
"VSS<4>"
$PN"274"15;
"VSS<5>"
$PN"272"15;
"VSS<6>"
$PN"270"15;
"VSS<7>"
$PN"268"15;
"VSS<8>"
$PN"265"15;
"VSS<9>"
$PN"263"15;
"VSS<10>"
$PN"261"15;
"VSS<11>"
$PN"259"15;
"VSS<12>"
$PN"257"15;
"VSS<13>"
$PN"254"15;
"VSS<14>"
$PN"252"15;
"VSS<15>"
$PN"250"15;
"VSS<16>"
$PN"248"15;
"VSS<17>"
$PN"246"15;
"VSS<18>"
$PN"243"15;
"VSS<19>"
$PN"241"15;
"VSS<20>"
$PN"239"15;
"VSS<21>"
$PN"202"15;
"VSS<22>"
$PN"200"15;
"VSS<23>"
$PN"198"15;
"VSS<24>"
$PN"195"15;
"VSS<25>"
$PN"193"15;
"VSS<26>"
$PN"191"15;
"VSS<27>"
$PN"189"15;
"VSS<28>"
$PN"187"15;
"VSS<29>"
$PN"184"15;
"VSS<30>"
$PN"182"15;
"VSS<31>"
$PN"180"15;
"VSS<32>"
$PN"178"15;
"VSS<33>"
$PN"176"15;
"VSS<34>"
$PN"173"15;
"VSS<35>"
$PN"171"15;
"VSS<36>"
$PN"169"15;
"VSS<37>"
$PN"167"15;
"VSS<38>"
$PN"165"15;
"VSS<39>"
$PN"162"15;
"VSS<40>"
$PN"160"15;
"VSS<41>"
$PN"158"15;
"VSS<42>"
$PN"156"15;
"VSS<43>"
$PN"154"15;
"VSS<44>"
$PN"151"15;
"VSS<47>"
$PN"138"14;
"VSS<48>"
$PN"136"14;
"VSS<49>"
$PN"134"14;
"VSS<50>"
$PN"131"14;
"VSS<51>"
$PN"129"14;
"VSS<52>"
$PN"127"14;
"VSS<53>"
$PN"125"14;
"VSS<54>"
$PN"123"14;
"VSS<55>"
$PN"120"14;
"VSS<56>"
$PN"118"14;
"VSS<57>"
$PN"116"14;
"VSS<58>"
$PN"114"14;
"VSS<59>"
$PN"112"14;
"VSS<60>"
$PN"109"14;
"VSS<61>"
$PN"107"14;
"VSS<62>"
$PN"105"14;
"VSS<63>"
$PN"103"14;
"VSS<64>"
$PN"101"14;
"VSS<65>"
$PN"98"14;
"VSS<66>"
$PN"96"14;
"VSS<67>"
$PN"94"14;
"VSS<68>"
$PN"57"14;
"VSS<69>"
$PN"55"14;
"VSS<70>"
$PN"53"14;
"VSS<71>"
$PN"50"14;
"VSS<72>"
$PN"48"14;
"VSS<73>"
$PN"46"14;
"VSS<74>"
$PN"44"14;
"VSS<75>"
$PN"42"14;
"VSS<76>"
$PN"39"14;
"VSS<77>"
$PN"37"14;
"VSS<78>"
$PN"35"14;
"VSS<79>"
$PN"33"14;
"VSS<80>"
$PN"31"14;
"VSS<81>"
$PN"28"14;
"VSS<82>"
$PN"26"14;
"VSS<83>"
$PN"24"14;
"VSS<84>"
$PN"22"14;
"VSS<85>"
$PN"20"14;
"VSS<86>"
$PN"17"14;
"VSS<87>"
$PN"15"14;
"VSS<45>"
$PN"149"15;
"VSS<46>"
$PN"147"15;
%"TAP"
"6","(-3150,4200)","0","mstr_standard","I26";
;
HDL_TAP"TRUE"
BODY_TYPE"PLUMBING"
CDS_LIB"mstr_standard";
"B \NAC \NWC"9;
"S \NAC"
BN"13"132;
%"SCONN288_H44441004"
"4","(-100,1700)","0","mstr_sconn","I260";
;
CDS_SEC"4"
ROOM"DDR4_CH_A"
CDS_LOCATION"J4G1"
SEC"4"
SEC_TYPE"PIP"
CDS_LIB"mstr_sconn"
BOM_COST"MEM"
PACK_TYPE"PIP"
MATERIAL"SCONN"
PART_NUMBER"H44441-004"
LOCATION"J4G1";
"VPP<4>"
$PN"142"18;
"VTT<1>"
$PN"77"20;
"VPP<0>"
$PN"287"18;
"VPP<1>"
$PN"286"18;
"VPP<2>"
$PN"288"18;
"VPP<3>"
$PN"143"18;
"VDD<1>"
$PN"233"13;
"VDD<2>"
$PN"231"13;
"VDD<3>"
$PN"229"13;
"VDD<4>"
$PN"226"13;
"VDD<5>"
$PN"223"13;
"VDD<7>"
$PN"217"13;
"VDD<8>"
$PN"215"13;
"VDD<9>"
$PN"212"13;
"VDD<11>"
$PN"206"13;
"VDD<12>"
$PN"204"13;
"VDD<14>"
$PN"90"13;
"VDD<15>"
$PN"88"13;
"VDD<17>"
$PN"83"13;
"VDD<18>"
$PN"80"13;
"VDD<20>"
$PN"73"13;
"VDD<21>"
$PN"70"13;
"VDD<22>"
$PN"67"13;
"VDD<24>"
$PN"61"13;
"12V<0>"
$PN"145"21;
"12V<1>"
$PN"1"21;
"VTT<0>"
$PN"221"20;
"VDD<25>"
$PN"59"13;
"VDD<23>"
$PN"64"13;
"VDD<19>"
$PN"76"13;
"VDD<16>"
$PN"85"13;
"VDD<13>"
$PN"92"13;
"VDD<10>"
$PN"209"13;
"VDD<6>"
$PN"220"13;
"VDD<0>"
$PN"236"13;
%"PVDDQ_ABC"
"1","(-1125,2250)","0","mstr_symbols","I263";
;
HDL_POWER"PVDDQ_ABC"
ROOM"DDR4_CH_A"
BODY_TYPE"PLUMBING"
CDS_LIB"mstr_symbols"
BOM_COST"MEM"
VOLTAGE"1.2V";
"G\NAC"13;
%"GND"
"1","(1050,1150)","2","mstr_symbols","I264";
;
HDL_POWER"GND"
ROOM"DDR4_CH_A"
BODY_TYPE"PLUMBING"
BOM_COST"MEM"
CDS_LIB"mstr_symbols"
SIZE"1B"
VOLTAGE"0";
"A\NAC"14;
%"GND"
"1","(2450,1150)","2","mstr_symbols","I265";
;
HDL_POWER"GND"
ROOM"DDR4_CH_A"
BODY_TYPE"PLUMBING"
SIZE"1B"
BOM_COST"MEM"
CDS_LIB"mstr_symbols"
VOLTAGE"0";
"A\NAC"15;
%"GND"
"1","(-5050,1400)","2","mstr_symbols","I267";
;
HDL_POWER"GND"
ROOM"DDR4_CH_A"
BODY_TYPE"PLUMBING"
SIZE"1B"
CDS_LIB"mstr_symbols"
BOM_COST"MEM"
VOLTAGE"0";
"A\NAC"16;
%"TAP"
"6","(-3150,4150)","0","mstr_standard","I27";
;
HDL_TAP"TRUE"
BODY_TYPE"PLUMBING"
CDS_LIB"mstr_standard";
"B \NAC \NWC"9;
"S \NAC"
BN"12"133;
%"GND"
"1","(-4350,800)","0","mstr_symbols","I271";
;
HDL_POWER"GND"
ROOM"DDR4_CH_A"
BODY_TYPE"PLUMBING"
BOM_COST"MEM"
CDS_LIB"mstr_symbols"
SIZE"1B"
VOLTAGE"0";
"A\NAC"17;
%"CAP_A"
"1","(-4350,1050)","2","dev_discrete","I272";
;
ROOM"DDR4_CH_A"
$SEC"1"
CDS_SEC"1"
CDS_LIB"dev_discrete"
BOM_COST"MEM"
CDS_LOCATION"C4F10"
MATERIAL"X7R"
VOLTAGE"25V"
PACK_TYPE"0402V"
TOLERANCE"10%"
VALUE"0.01UF"
PART_NUMBER"A36096-045"
LOCATION"C4F10";
"B"
$PN"2"17;
"A"
$PN"1"22;
%"PVPP_ABC"
"1","(-750,2700)","0","mstr_symbols","I273";
;
HDL_POWER"PVPP_ABC"
ROOM"DDR4_CH_A"
BODY_TYPE"PLUMBING"
CDS_LIB"mstr_symbols"
BOM_COST"MEM"
VOLTAGE"2.5V";
"G\NAC"18;
%"PVPP_ABC"
"1","(-5050,1750)","0","mstr_symbols","I274";
;
HDL_POWER"PVPP_ABC"
ROOM"DDR4_CH_A"
BODY_TYPE"PLUMBING"
CDS_LIB"mstr_symbols"
BOM_COST"MEM"
VOLTAGE"2.5V";
"G\NAC"19;
%"PVTT_ABC"
"1","(-900,2400)","0","mstr_symbols","I275";
;
HDL_POWER"PVTT_ABC"
ROOM"DDR4_CH_A"
BODY_TYPE"PLUMBING"
CDS_LIB"mstr_symbols"
BOM_COST"MEM"
VOLTAGE"0.6V";
"G\NAC"20;
%"TAP"
"6","(-3150,4100)","0","mstr_standard","I28";
;
HDL_TAP"TRUE"
BODY_TYPE"PLUMBING"
CDS_LIB"mstr_standard";
"B \NAC \NWC"9;
"S \NAC"
BN"11"130;
%"P12V_NVDIMM_ABC"
"1","(600,2775)","0","mstr_symbols","I289";
;
HDL_POWER"P12V_NVDIMM_ABC"
BODY_TYPE"PLUMBING"
CDS_LIB"mstr_symbols"
VOLTAGE"12.0";
"G\NAC"21;
%"TAP"
"6","(-3150,4050)","0","mstr_standard","I29";
;
HDL_TAP"TRUE"
BODY_TYPE"PLUMBING"
CDS_LIB"mstr_standard";
"B \NAC \NWC"9;
"S \NAC"
BN"10"39;
%"TAP"
"6","(-3150,4000)","0","mstr_standard","I30";
;
HDL_TAP"TRUE"
BODY_TYPE"PLUMBING"
CDS_LIB"mstr_standard";
"B \NAC \NWC"9;
"S \NAC"
BN"9"52;
%"TAP"
"6","(-3150,3950)","0","mstr_standard","I31";
;
HDL_TAP"TRUE"
BODY_TYPE"PLUMBING"
CDS_LIB"mstr_standard";
"B \NAC \NWC"9;
"S \NAC"
BN"8"53;
%"TAP"
"6","(-3150,3850)","0","mstr_standard","I32";
;
HDL_TAP"TRUE"
BODY_TYPE"PLUMBING"
CDS_LIB"mstr_standard";
"B \NAC \NWC"9;
"S \NAC"
BN"6"55;
%"TAP"
"6","(-3150,3900)","0","mstr_standard","I33";
;
HDL_TAP"TRUE"
BODY_TYPE"PLUMBING"
CDS_LIB"mstr_standard";
"B \NAC \NWC"9;
"S \NAC"
BN"7"54;
%"TAP"
"6","(-3150,3800)","0","mstr_standard","I34";
;
HDL_TAP"TRUE"
BODY_TYPE"PLUMBING"
CDS_LIB"mstr_standard";
"B \NAC \NWC"9;
"S \NAC"
BN"5"56;
%"TAP"
"6","(-3150,3700)","0","mstr_standard","I35";
;
HDL_TAP"TRUE"
BODY_TYPE"PLUMBING"
CDS_LIB"mstr_standard";
"B \NAC \NWC"9;
"S \NAC"
BN"3"58;
%"TAP"
"6","(-3150,3750)","0","mstr_standard","I36";
;
HDL_TAP"TRUE"
BODY_TYPE"PLUMBING"
CDS_LIB"mstr_standard";
"B \NAC \NWC"9;
"S \NAC"
BN"4"57;
%"TAP"
"6","(-3150,3650)","0","mstr_standard","I37";
;
HDL_TAP"TRUE"
BODY_TYPE"PLUMBING"
CDS_LIB"mstr_standard";
"B \NAC \NWC"9;
"S \NAC"
BN"2"40;
%"TAP"
"6","(-3150,3600)","0","mstr_standard","I38";
;
HDL_TAP"TRUE"
BODY_TYPE"PLUMBING"
CDS_LIB"mstr_standard";
"B \NAC \NWC"9;
"S \NAC"
BN"1"59;
%"TAP"
"6","(-3150,3550)","0","mstr_standard","I39";
;
HDL_TAP"TRUE"
BODY_TYPE"PLUMBING"
CDS_LIB"mstr_standard";
"B \NAC \NWC"9;
"S \NAC"
BN"0"60;
%"TAP"
"6","(-3150,3300)","0","mstr_standard","I43";
;
HDL_TAP"TRUE"
BODY_TYPE"PLUMBING"
CDS_LIB"mstr_standard";
"B \NAC \NWC"12;
"S \NAC"
BN"0"43;
%"TAP"
"6","(-3150,3350)","0","mstr_standard","I44";
;
HDL_TAP"TRUE"
BODY_TYPE"PLUMBING"
CDS_LIB"mstr_standard";
"B \NAC \NWC"12;
"S \NAC"
BN"1"42;
%"TAP"
"6","(-3150,3450)","0","mstr_standard","I45";
;
HDL_TAP"TRUE"
BODY_TYPE"PLUMBING"
CDS_LIB"mstr_standard";
"B \NAC \NWC"7;
"S \NAC"
BN"1"65;
%"TAP"
"6","(-3150,3400)","0","mstr_standard","I46";
;
HDL_TAP"TRUE"
BODY_TYPE"PLUMBING"
CDS_LIB"mstr_standard";
"B \NAC \NWC"7;
"S \NAC"
BN"0"41;
%"TAP"
"6","(-3150,2350)","0","mstr_standard","I49";
;
HDL_TAP"TRUE"
BODY_TYPE"PLUMBING"
CDS_LIB"mstr_standard";
"B \NAC \NWC"10;
"S \NAC"
BN"6"38;
%"TAP"
"6","(-3150,2300)","0","mstr_standard","I50";
;
HDL_TAP"TRUE"
BODY_TYPE"PLUMBING"
CDS_LIB"mstr_standard";
"B \NAC \NWC"10;
"S \NAC"
BN"7"51;
%"TAP"
"6","(-3150,2250)","0","mstr_standard","I51";
;
HDL_TAP"TRUE"
BODY_TYPE"PLUMBING"
CDS_LIB"mstr_standard";
"B \NAC \NWC"10;
"S \NAC"
BN"4"50;
%"TAP"
"6","(-3150,2200)","0","mstr_standard","I52";
;
HDL_TAP"TRUE"
BODY_TYPE"PLUMBING"
CDS_LIB"mstr_standard";
"B \NAC \NWC"10;
"S \NAC"
BN"5"49;
%"TAP"
"6","(-3150,2150)","0","mstr_standard","I53";
;
HDL_TAP"TRUE"
BODY_TYPE"PLUMBING"
CDS_LIB"mstr_standard";
"B \NAC \NWC"10;
"S \NAC"
BN"2"48;
%"TAP"
"6","(-3150,2050)","0","mstr_standard","I54";
;
HDL_TAP"TRUE"
BODY_TYPE"PLUMBING"
CDS_LIB"mstr_standard";
"B \NAC \NWC"10;
"S \NAC"
BN"0"46;
%"TAP"
"6","(-3150,2100)","0","mstr_standard","I55";
;
HDL_TAP"TRUE"
BODY_TYPE"PLUMBING"
CDS_LIB"mstr_standard";
"B \NAC \NWC"10;
"S \NAC"
BN"3"47;
%"TAP"
"6","(-3150,2000)","0","mstr_standard","I56";
;
HDL_TAP"TRUE"
BODY_TYPE"PLUMBING"
CDS_LIB"mstr_standard";
"B \NAC \NWC"10;
"S \NAC"
BN"1"26;
END.
